# T6G (Grand Teton) — schematic netlist excerpt (pin names and nets, part order shuffled) for the footprints in the layout excerpt that follows; sources: Cadence DE-HDL packaged netlist, KiCad conversion of 04192023_DAF0TMB3IC0_F0TG_MB_C_brd_V02_OCP.brd

C1989  Q_CAP_DIFFBUS  DIFF BUS_0.22UF 6.3V 20% X6S  pkg C0201  page 67 : \1\ = P3E_CPU0_P4_TX_C_DP<3> ; \2\ = P3E_CPU0_P4_TX_DP<3>
R3184  Q_RES  4.7K 1% CHIP  pkg 0402LF  page 139 : A = P3V3_AUX ; B = OCP_V3_2_WAKE_BUFF_N
C952  Q_CAP_DIFFBUS  DIFF BUS_0.22UF 6.3V 20% X6S  pkg C0201  page 63 : \1\ = P5E_CPU0_P1_TX_C_DN<6> ; \2\ = P5E_CPU0_P1_TX_DN<6>

(kicad_pcb
	(version 20260206)
	(generator "pcbnew")
	(generator_version "10.0")
	(general
		(thickness 1.6)
		(legacy_teardrops no)
	)
	(paper "A4")
	(title_block
		(title "04192023_DAF0TMB3IC0_F0TG_MB_C_brd_V02_OCP.brd")
		(comment 1 "Grand Teton / footprints 738-740 of 8354")
	)
	(layers
		(0 "F.Cu" signal "TOP")
		(4 "In1.Cu" signal "GND")
		(6 "In2.Cu" signal "IN1")
		(8 "In3.Cu" signal "GND1")
		(10 "In4.Cu" signal "IN2")
		(12 "In5.Cu" signal "GND2")
		(14 "In6.Cu" signal "IN3")
		(16 "In7.Cu" signal "GND3")
		(18 "In8.Cu" signal "VCC")
		(20 "In9.Cu" signal "VCC1")
		(22 "In10.Cu" signal "GND4")
		(24 "In11.Cu" signal "IN4")
		(26 "In12.Cu" signal "GND5")
		(28 "In13.Cu" signal "IN5")
		(30 "In14.Cu" signal "GND6")
		(32 "In15.Cu" signal "IN6")
		(34 "In16.Cu" signal "GND7")
		(2 "B.Cu" signal "BOTTOM")
		(9 "F.Adhes" user "F.Adhesive")
		(11 "B.Adhes" user "B.Adhesive")
		(13 "F.Paste" user "Package Geometry/Pastemask Top")
		(15 "B.Paste" user "Package Geometry/Pastemask Bottom")
		(5 "F.SilkS" user "Ref Des/Silkscreen Top")
		(7 "B.SilkS" user "Ref Des/Silkscreen Bottom")
		(1 "F.Mask" user "Board Geometry/Soldermask Top")
		(3 "B.Mask" user "Board Geometry/Soldermask Bottom")
		(17 "Dwgs.User" user "User.Drawings")
		(19 "Cmts.User" user "User.Comments")
		(21 "Eco1.User" user "User.Eco1")
		(23 "Eco2.User" user "User.Eco2")
		(25 "Edge.Cuts" user "Board Geometry/Outline")
		(27 "Margin" user)
		(31 "F.CrtYd" user "Package Geometry/Place Bound Top")
		(29 "B.CrtYd" user "Package Geometry/Place Bound Bottom")
		(35 "F.Fab" user "Ref Des/Assembly Top")
		(33 "B.Fab" user "Ref Des/Assembly Bottom")
	)
	(footprint ""
		(layer "F.Cu")
		(at 94.605602 -40.139112)
		(property "Reference" "R3184"
			(at 0 0 0)
			(layer "F.SilkS")
			(hide yes)
			(effects
				(font
					(size 1.27 1.27)
				)
			)
		)
		(property "Value" ""
			(at 0 0 0)
			(layer "F.Fab")
			(effects
				(font
					(size 1.27 1.27)
				)
			)
		)
		(duplicate_pad_numbers_are_jumpers no)
		(fp_line
			(start -0.7874 -0.4064)
			(end 0.7874 -0.4064)
			(stroke
				(width 0.1524)
				(type default)
			)
			(layer "F.SilkS")
		)
		(fp_line
			(start -0.7874 0.4064)
			(end -0.7874 -0.4064)
			(stroke
				(width 0.1524)
				(type default)
			)
			(layer "F.SilkS")
		)
		(fp_line
			(start 0.7874 -0.4064)
			(end 0.7874 0.4064)
			(stroke
				(width 0.1524)
				(type default)
			)
			(layer "F.SilkS")
		)
		(fp_line
			(start 0.7874 0.4064)
			(end -0.7874 0.4064)
			(stroke
				(width 0.1524)
				(type default)
			)
			(layer "F.SilkS")
		)
		(fp_line
			(start -0.67945 -0.305054)
			(end -0.12065 -0.305054)
			(stroke
				(width 0.1)
				(type default)
			)
			(layer "F.Fab")
		)
		(fp_line
			(start -0.67945 0.3048)
			(end -0.67945 -0.305054)
			(stroke
				(width 0.1)
				(type default)
			)
			(layer "F.Fab")
		)
		(fp_line
			(start -0.12065 -0.305054)
			(end -0.12065 -0.2794)
			(stroke
				(width 0.1)
				(type default)
			)
			(layer "F.Fab")
		)
		(fp_line
			(start -0.12065 -0.2794)
			(end 0.12065 -0.2794)
			(stroke
				(width 0.1)
				(type default)
			)
			(layer "F.Fab")
		)
		(fp_line
			(start -0.12065 0.2794)
			(end -0.12065 0.3048)
			(stroke
				(width 0.1)
				(type default)
			)
			(layer "F.Fab")
		)
		(fp_line
			(start -0.12065 0.3048)
			(end -0.67945 0.3048)
			(stroke
				(width 0.1)
				(type default)
			)
			(layer "F.Fab")
		)
		(fp_line
			(start 0.120396 0.2794)
			(end -0.12065 0.2794)
			(stroke
				(width 0.1)
				(type default)
			)
			(layer "F.Fab")
		)
		(fp_line
			(start 0.120396 0.3048)
			(end 0.120396 0.2794)
			(stroke
				(width 0.1)
				(type default)
			)
			(layer "F.Fab")
		)
		(fp_line
			(start 0.12065 -0.3048)
			(end 0.67945 -0.3048)
			(stroke
				(width 0.1)
				(type default)
			)
			(layer "F.Fab")
		)
		(fp_line
			(start 0.12065 -0.2794)
			(end 0.12065 -0.3048)
			(stroke
				(width 0.1)
				(type default)
			)
			(layer "F.Fab")
		)
		(fp_line
			(start 0.67945 -0.3048)
			(end 0.67945 0.3048)
			(stroke
				(width 0.1)
				(type default)
			)
			(layer "F.Fab")
		)
		(fp_line
			(start 0.67945 0.3048)
			(end 0.120396 0.3048)
			(stroke
				(width 0.1)
				(type default)
			)
			(layer "F.Fab")
		)
		(pad "1" smd circle
			(at -0.40005 0)
			(size 0 0)
			(layers "F.Cu" "F.Mask" "F.Paste")
			(net "P3V3_AUX")
		)
		(pad "2" smd circle
			(at 0.40005 0)
			(size 0 0)
			(layers "F.Cu" "F.Mask" "F.Paste")
			(net "OCP_V3_2_WAKE_BUFF_N")
		)
	)
	(footprint ""
		(layer "F.Cu")
		(at 340.940644 -378.95403 -90)
		(property "Reference" "C952"
			(at 0 0 270)
			(layer "F.SilkS")
			(hide yes)
			(effects
				(font
					(size 1.27 1.27)
				)
			)
		)
		(property "Value" ""
			(at 0 0 270)
			(layer "F.Fab")
			(effects
				(font
					(size 1.27 1.27)
				)
			)
		)
		(duplicate_pad_numbers_are_jumpers no)
		(fp_line
			(start -0.299974 0.150114)
			(end -0.299974 -0.150114)
			(stroke
				(width 0.1)
				(type default)
			)
			(layer "F.Fab")
		)
		(fp_line
			(start 0.299974 0.150114)
			(end -0.299974 0.150114)
			(stroke
				(width 0.1)
				(type default)
			)
			(layer "F.Fab")
		)
		(fp_line
			(start -0.299974 -0.150114)
			(end 0.299974 -0.150114)
			(stroke
				(width 0.1)
				(type default)
			)
			(layer "F.Fab")
		)
		(fp_line
			(start 0.299974 -0.150114)
			(end 0.299974 0.150114)
			(stroke
				(width 0.1)
				(type default)
			)
			(layer "F.Fab")
		)
		(pad "1" smd rect
			(at -0.2667 0 270)
			(size 0.3048 0.381)
			(layers "F.Cu" "F.Mask" "F.Paste")
			(net "P5E_CPU0_P1_TX_C_DN<6>")
		)
		(pad "2" smd rect
			(at 0.2667 0 270)
			(size 0.3048 0.381)
			(layers "F.Cu" "F.Mask" "F.Paste")
			(net "P5E_CPU0_P1_TX_DN<6>")
		)
	)
	(footprint ""
		(layer "F.Cu")
		(at 239.152684 -58.32729)
		(property "Reference" "C1989"
			(at 0 0 0)
			(layer "F.SilkS")
			(hide yes)
			(effects
				(font
					(size 1.27 1.27)
				)
			)
		)
		(property "Value" ""
			(at 0 0 0)
			(layer "F.Fab")
			(effects
				(font
					(size 1.27 1.27)
				)
			)
		)
		(duplicate_pad_numbers_are_jumpers no)
		(fp_line
			(start -0.299974 -0.150114)
			(end 0.299974 -0.150114)
			(stroke
				(width 0.1)
				(type default)
			)
			(layer "F.Fab")
		)
		(fp_line
			(start -0.299974 0.150114)
			(end -0.299974 -0.150114)
			(stroke
				(width 0.1)
				(type default)
			)
			(layer "F.Fab")
		)
		(fp_line
			(start 0.299974 -0.150114)
			(end 0.299974 0.150114)
			(stroke
				(width 0.1)
				(type default)
			)
			(layer "F.Fab")
		)
		(fp_line
			(start 0.299974 0.150114)
			(end -0.299974 0.150114)
			(stroke
				(width 0.1)
				(type default)
			)
			(layer "F.Fab")
		)
		(pad "1" smd rect
			(at -0.2667 0)
			(size 0.3048 0.381)
			(layers "F.Cu" "F.Mask" "F.Paste")
			(net "P3E_CPU0_P4_TX_C_DP<3>")
		)
		(pad "2" smd rect
			(at 0.2667 0)
			(size 0.3048 0.381)
			(layers "F.Cu" "F.Mask" "F.Paste")
			(net "P3E_CPU0_P4_TX_DP<3>")
		)
	)
)
